# T6G (Grand Teton) — schematic netlist excerpt (pin names and nets, part order shuffled) for the footprints in the layout excerpt that follows; sources: Cadence DE-HDL packaged netlist, KiCad conversion of 04192023_DAF0TMB3IC0_F0TG_MB_C_brd_V02_OCP.brd

PR518  Q_RES  1.5 1% EMPTY  pkg 0402LF  page 220 : A = SW_PVDDCR_CPU1_P1_SW6_RC ; B = GND
R8083  Q_RES  0 5% CHIP  pkg 0402LF  page 92 : A = PWRGD_CHGL_CPU0 ; B = PWRGD_CHGL_CPU0_R1

(kicad_pcb
	(version 20260206)
	(generator "pcbnew")
	(generator_version "10.0")
	(general
		(thickness 1.6)
		(legacy_teardrops no)
	)
	(paper "A4")
	(title_block
		(title "04192023_DAF0TMB3IC0_F0TG_MB_C_brd_V02_OCP.brd")
		(comment 1 "Grand Teton / footprints 1428-1429 of 8354")
	)
	(layers
		(0 "F.Cu" signal "TOP")
		(4 "In1.Cu" signal "GND")
		(6 "In2.Cu" signal "IN1")
		(8 "In3.Cu" signal "GND1")
		(10 "In4.Cu" signal "IN2")
		(12 "In5.Cu" signal "GND2")
		(14 "In6.Cu" signal "IN3")
		(16 "In7.Cu" signal "GND3")
		(18 "In8.Cu" signal "VCC")
		(20 "In9.Cu" signal "VCC1")
		(22 "In10.Cu" signal "GND4")
		(24 "In11.Cu" signal "IN4")
		(26 "In12.Cu" signal "GND5")
		(28 "In13.Cu" signal "IN5")
		(30 "In14.Cu" signal "GND6")
		(32 "In15.Cu" signal "IN6")
		(34 "In16.Cu" signal "GND7")
		(2 "B.Cu" signal "BOTTOM")
		(9 "F.Adhes" user "F.Adhesive")
		(11 "B.Adhes" user "B.Adhesive")
		(13 "F.Paste" user "Package Geometry/Pastemask Top")
		(15 "B.Paste" user "Package Geometry/Pastemask Bottom")
		(5 "F.SilkS" user "Ref Des/Silkscreen Top")
		(7 "B.SilkS" user "Ref Des/Silkscreen Bottom")
		(1 "F.Mask" user "Board Geometry/Soldermask Top")
		(3 "B.Mask" user "Board Geometry/Soldermask Bottom")
		(17 "Dwgs.User" user "User.Drawings")
		(19 "Cmts.User" user "User.Comments")
		(21 "Eco1.User" user "User.Eco1")
		(23 "Eco2.User" user "User.Eco2")
		(25 "Edge.Cuts" user "Board Geometry/Outline")
		(27 "Margin" user)
		(31 "F.CrtYd" user "Package Geometry/Place Bound Top")
		(29 "B.CrtYd" user "Package Geometry/Place Bound Bottom")
		(35 "F.Fab" user "Ref Des/Assembly Top")
		(33 "B.Fab" user "Ref Des/Assembly Bottom")
	)
	(footprint ""
		(layer "F.Cu")
		(at 100.052124 -338.205064 90)
		(property "Reference" "PR518"
			(at 0 0 90)
			(layer "F.SilkS")
			(hide yes)
			(effects
				(font
					(size 1.27 1.27)
				)
			)
		)
		(property "Value" ""
			(at 0 0 90)
			(layer "F.Fab")
			(effects
				(font
					(size 1.27 1.27)
				)
			)
		)
		(duplicate_pad_numbers_are_jumpers no)
		(fp_line
			(start 0.7874 -0.4064)
			(end 0.7874 0.4064)
			(stroke
				(width 0.1524)
				(type default)
			)
			(layer "F.SilkS")
		)
		(fp_line
			(start -0.7874 -0.4064)
			(end 0.7874 -0.4064)
			(stroke
				(width 0.1524)
				(type default)
			)
			(layer "F.SilkS")
		)
		(fp_line
			(start 0.7874 0.4064)
			(end -0.7874 0.4064)
			(stroke
				(width 0.1524)
				(type default)
			)
			(layer "F.SilkS")
		)
		(fp_line
			(start -0.7874 0.4064)
			(end -0.7874 -0.4064)
			(stroke
				(width 0.1524)
				(type default)
			)
			(layer "F.SilkS")
		)
		(fp_line
			(start -0.12065 -0.305054)
			(end -0.12065 -0.2794)
			(stroke
				(width 0.1)
				(type default)
			)
			(layer "F.Fab")
		)
		(fp_line
			(start -0.67945 -0.305054)
			(end -0.12065 -0.305054)
			(stroke
				(width 0.1)
				(type default)
			)
			(layer "F.Fab")
		)
		(fp_line
			(start 0.67945 -0.3048)
			(end 0.67945 0.3048)
			(stroke
				(width 0.1)
				(type default)
			)
			(layer "F.Fab")
		)
		(fp_line
			(start 0.12065 -0.3048)
			(end 0.67945 -0.3048)
			(stroke
				(width 0.1)
				(type default)
			)
			(layer "F.Fab")
		)
		(fp_line
			(start 0.12065 -0.2794)
			(end 0.12065 -0.3048)
			(stroke
				(width 0.1)
				(type default)
			)
			(layer "F.Fab")
		)
		(fp_line
			(start -0.12065 -0.2794)
			(end 0.12065 -0.2794)
			(stroke
				(width 0.1)
				(type default)
			)
			(layer "F.Fab")
		)
		(fp_line
			(start 0.120396 0.2794)
			(end -0.12065 0.2794)
			(stroke
				(width 0.1)
				(type default)
			)
			(layer "F.Fab")
		)
		(fp_line
			(start -0.12065 0.2794)
			(end -0.12065 0.3048)
			(stroke
				(width 0.1)
				(type default)
			)
			(layer "F.Fab")
		)
		(fp_line
			(start 0.67945 0.3048)
			(end 0.120396 0.3048)
			(stroke
				(width 0.1)
				(type default)
			)
			(layer "F.Fab")
		)
		(fp_line
			(start 0.120396 0.3048)
			(end 0.120396 0.2794)
			(stroke
				(width 0.1)
				(type default)
			)
			(layer "F.Fab")
		)
		(fp_line
			(start -0.12065 0.3048)
			(end -0.67945 0.3048)
			(stroke
				(width 0.1)
				(type default)
			)
			(layer "F.Fab")
		)
		(fp_line
			(start -0.67945 0.3048)
			(end -0.67945 -0.305054)
			(stroke
				(width 0.1)
				(type default)
			)
			(layer "F.Fab")
		)
		(pad "1" smd circle
			(at -0.40005 0 90)
			(size 0 0)
			(layers "F.Cu" "F.Mask" "F.Paste")
			(net "SW_PVDDCR_CPU1_P1_SW6_RC")
		)
		(pad "2" smd circle
			(at 0.40005 0 90)
			(size 0 0)
			(layers "F.Cu" "F.Mask" "F.Paste")
			(net "GND")
		)
	)
	(footprint ""
		(layer "F.Cu")
		(at 204.978 -99.695 180)
		(property "Reference" "R8083"
			(at 0 0 180)
			(layer "F.SilkS")
			(hide yes)
			(effects
				(font
					(size 1.27 1.27)
				)
			)
		)
		(property "Value" ""
			(at 0 0 180)
			(layer "F.Fab")
			(effects
				(font
					(size 1.27 1.27)
				)
			)
		)
		(duplicate_pad_numbers_are_jumpers no)
		(fp_line
			(start 0.7874 0.4064)
			(end -0.7874 0.4064)
			(stroke
				(width 0.1524)
				(type default)
			)
			(layer "F.SilkS")
		)
		(fp_line
			(start 0.7874 -0.4064)
			(end 0.7874 0.4064)
			(stroke
				(width 0.1524)
				(type default)
			)
			(layer "F.SilkS")
		)
		(fp_line
			(start -0.7874 0.4064)
			(end -0.7874 -0.4064)
			(stroke
				(width 0.1524)
				(type default)
			)
			(layer "F.SilkS")
		)
		(fp_line
			(start -0.7874 -0.4064)
			(end 0.7874 -0.4064)
			(stroke
				(width 0.1524)
				(type default)
			)
			(layer "F.SilkS")
		)
		(fp_line
			(start 0.67945 0.3048)
			(end 0.120396 0.3048)
			(stroke
				(width 0.1)
				(type default)
			)
			(layer "F.Fab")
		)
		(fp_line
			(start 0.67945 -0.3048)
			(end 0.67945 0.3048)
			(stroke
				(width 0.1)
				(type default)
			)
			(layer "F.Fab")
		)
		(fp_line
			(start 0.12065 -0.2794)
			(end 0.12065 -0.3048)
			(stroke
				(width 0.1)
				(type default)
			)
			(layer "F.Fab")
		)
		(fp_line
			(start 0.12065 -0.3048)
			(end 0.67945 -0.3048)
			(stroke
				(width 0.1)
				(type default)
			)
			(layer "F.Fab")
		)
		(fp_line
			(start 0.120396 0.3048)
			(end 0.120396 0.2794)
			(stroke
				(width 0.1)
				(type default)
			)
			(layer "F.Fab")
		)
		(fp_line
			(start 0.120396 0.2794)
			(end -0.12065 0.2794)
			(stroke
				(width 0.1)
				(type default)
			)
			(layer "F.Fab")
		)
		(fp_line
			(start -0.12065 0.3048)
			(end -0.67945 0.3048)
			(stroke
				(width 0.1)
				(type default)
			)
			(layer "F.Fab")
		)
		(fp_line
			(start -0.12065 0.2794)
			(end -0.12065 0.3048)
			(stroke
				(width 0.1)
				(type default)
			)
			(layer "F.Fab")
		)
		(fp_line
			(start -0.12065 -0.2794)
			(end 0.12065 -0.2794)
			(stroke
				(width 0.1)
				(type default)
			)
			(layer "F.Fab")
		)
		(fp_line
			(start -0.12065 -0.305054)
			(end -0.12065 -0.2794)
			(stroke
				(width 0.1)
				(type default)
			)
			(layer "F.Fab")
		)
		(fp_line
			(start -0.67945 0.3048)
			(end -0.67945 -0.305054)
			(stroke
				(width 0.1)
				(type default)
			)
			(layer "F.Fab")
		)
		(fp_line
			(start -0.67945 -0.305054)
			(end -0.12065 -0.305054)
			(stroke
				(width 0.1)
				(type default)
			)
			(layer "F.Fab")
		)
		(pad "1" smd circle
			(at -0.40005 0 180)
			(size 0 0)
			(layers "F.Cu" "F.Mask" "F.Paste")
			(net "PWRGD_CHGL_CPU0")
		)
		(pad "2" smd circle
			(at 0.40005 0 180)
			(size 0 0)
			(layers "F.Cu" "F.Mask" "F.Paste")
			(net "PWRGD_CHGL_CPU0_R1")
		)
	)
)
